# S9S_MB_2U (Grand Teton) — schematic netlist excerpt (pin names and nets, part order shuffled) for the footprints in the layout excerpt that follows; sources: Cadence DE-HDL packaged netlist, KiCad conversion of 03242023_DA0F0TMBIJ0_F0T_Motherboard_J_brd_V01_OCP.brd

J29  SCONN288_ADR50017P130CC  SCONN288_ADR50017-P130CC IO  pkg DDR288S_1-1VXB  page 110
  VIN_BULK0  = P12V_S3_AUX_CPU1_NVDIMM
  RFU0  = TP_CHG_CPU1_DIMM1_FRU_0
  VIN_MGMT  = P3V3_AUX
  HSCL  = I3C_SPD_DDREFGH_CPU1_LVC1_SCL_4
  HSDA  = I3C_SPD_DDREFGH_CPU1_LVC1_SDA
  VSS0  = GND
  DQ0_A  = M_G_CPU1_SA_DQ<0>
  VSS1  = GND
  DQ1_A  = M_G_CPU1_SA_DQ<1>
  VSS2  = GND
  DQS0_A_T  = M_G_CPU1_SA_DQS_DP<0>
  DQS0_A_C  = M_G_CPU1_SA_DQS_DN<0>
  VSS3  = GND
  DQ4_A  = M_G_CPU1_SA_DQ<4>
  VSS4  = GND
  DQ5_A  = M_G_CPU1_SA_DQ<5>
  VSS5  = GND
  DQ8_A  = M_G_CPU1_SA_DQ<8>
  VSS6  = GND
  DQ9_A  = M_G_CPU1_SA_DQ<9>
  VSS7  = GND
  DQS1_A_T  = M_G_CPU1_SA_DQS_DP<1>
  DQS1_A_C  = M_G_CPU1_SA_DQS_DN<1>
  VSS8  = GND
  DQ12_A  = M_G_CPU1_SA_DQ<12>
  VSS9  = GND
  DQ13_A  = M_G_CPU1_SA_DQ<13>
  VSS10  = GND
  DQ16_A  = M_G_CPU1_SA_DQ<16>
  VSS11  = GND
  DQ17_A  = M_G_CPU1_SA_DQ<17>
  VSS12  = GND
  DQS2_A_T  = M_G_CPU1_SA_DQS_DP<2>
  DQS2_A_C  = M_G_CPU1_SA_DQS_DN<2>
  VSS13  = GND
  DQ20_A  = M_G_CPU1_SA_DQ<20>
  VSS14  = GND
  DQ21_A  = M_G_CPU1_SA_DQ<21>
  VSS15  = GND
  DQ24_A  = M_G_CPU1_SA_DQ<24>
  VSS16  = GND
  DQ25_A  = M_G_CPU1_SA_DQ<25>
  VSS17  = GND
  DQS3_A_T  = M_G_CPU1_SA_DQS_DP<3>
  DQS3_A_C  = M_G_CPU1_SA_DQS_DN<3>
  VSS18  = GND
  DQ28_A  = M_G_CPU1_SA_DQ<28>
  VSS19  = GND
  DQ29_A  = M_G_CPU1_SA_DQ<29>
  VSS20  = GND
  CB0_A  = M_G_CPU1_SA_CB<0>
  VSS21  = GND
  CB1_A  = M_G_CPU1_SA_CB<1>
  VSS22  = GND
  DQS4_A_T  = M_G_CPU1_SA_DQS_DP<4>
  DQS4_A_C  = M_G_CPU1_SA_DQS_DN<4>
  VSS23  = GND
  CB4_A  = M_G_CPU1_SA_CB<4>
  VSS24  = GND
  CB5_A  = M_G_CPU1_SA_CB<5>
  VSS25  = GND
  ALERT_N  = M_G_CPU1_ALERT_N
  VSS26  = GND
  CS0_A_N  = M_G_CPU1_SA_CS_N<0>
  VSS27  = GND
  CA0_A  = M_G_CPU1_SA_CA<0>
  VSS28  = GND
  CA2_A  = M_G_CPU1_SA_CA<2>
  VSS29  = GND
  CA4_A  = M_G_CPU1_SA_CA<4>
  VSS30  = GND
  CA6_A  = M_G_CPU1_SA_CA<6>
  VSS31  = GND
  PAR_A  = M_G_CPU1_SA_PAR
  VSS32  = GND
  CA0_B  = M_G_CPU1_SB_CA<0>
  VSS33  = GND
  CA2_B  = M_G_CPU1_SB_CA<2>
  VSS34  = GND
  CA4_B  = M_G_CPU1_SB_CA<4>
  VSS35  = GND
  CA6_B  = M_G_CPU1_SB_CA<6>
  VSS36  = GND
  CS0_B_N  = M_G_CPU1_SB_CS_N<0>
  VSS37  = GND
  \lbd||rsp_a_n\  = M_G_CPU1_SA_RSP<0>
  \lbs||rsp_b_n\  = M_G_CPU1_SB_RSP<0>
  VSS38  = GND
  CB4_B  = M_G_CPU1_SB_CB<4>
  VSS39  = GND
  CB5_B  = M_G_CPU1_SB_CB<5>
  VSS40  = GND
  \dqs9_b_t||tdqs9_b_t||dbi4_b_n\  = M_G_CPU1_SB_DQS_DP<9>
  \dqs9_b_c||tdqs9_b_c\  = M_G_CPU1_SB_DQS_DN<9>
  VSS41  = GND
  CB0_B  = M_G_CPU1_SB_CB<0>
  VSS42  = GND
  CB1_B  = M_G_CPU1_SB_CB<1>
  VSS43  = GND
  DQ0_B  = M_G_CPU1_SB_DQ<0>
  VSS44  = GND
  DQ1_B  = M_G_CPU1_SB_DQ<1>
  VSS45  = GND
  DQS0_B_T  = M_G_CPU1_SB_DQS_DP<0>
  DQS0_B_C  = M_G_CPU1_SB_DQS_DN<0>
  VSS46  = GND
  DQ4_B  = M_G_CPU1_SB_DQ<4>
  VSS47  = GND
  DQ5_B  = M_G_CPU1_SB_DQ<5>
  VSS48  = GND
  DQ8_B  = M_G_CPU1_SB_DQ<8>
  VSS49  = GND
  DQ9_B  = M_G_CPU1_SB_DQ<9>
  VSS50  = GND
  DQS1_B_T  = M_G_CPU1_SB_DQS_DP<1>
  DQS1_B_C  = M_G_CPU1_SB_DQS_DN<1>
  VSS51  = GND
  DQ12_B  = M_G_CPU1_SB_DQ<12>
  VSS52  = GND
  DQ13_B  = M_G_CPU1_SB_DQ<13>
  VSS53  = GND
  DQ16_B  = M_G_CPU1_SB_DQ<16>
  VSS54  = GND
  DQ17_B  = M_G_CPU1_SB_DQ<17>
  VSS55  = GND
  DQS2_B_T  = M_G_CPU1_SB_DQS_DP<2>
  DQS2_B_C  = M_G_CPU1_SB_DQS_DN<2>
  VSS56  = GND
  DQ20_B  = M_G_CPU1_SB_DQ<20>
  VSS57  = GND
  DQ21_B  = M_G_CPU1_SB_DQ<21>
  VSS58  = GND
  DQ24_B  = M_G_CPU1_SB_DQ<24>
  VSS59  = GND
  DQ25_B  = M_G_CPU1_SB_DQ<25>
  VSS60  = GND
  DQS3_B_T  = M_G_CPU1_SB_DQS_DP<3>
  DQS3_B_C  = M_G_CPU1_SB_DQS_DN<3>
  VSS61  = GND
  DQ28_B  = M_G_CPU1_SB_DQ<28>
  VSS62  = GND
  DQ29_B  = M_G_CPU1_SB_DQ<29>
  VSS63  = GND
  RFU1  = TP_CHG_CPU1_DIMM1_FRU_1
  VIN_BULK1  = P12V_S3_AUX_CPU1_NVDIMM
  VIN_BULK2  = P12V_S3_AUX_CPU1_NVDIMM
  \pwr_good||fail_n\  = PWRGD_CHG_CPU1_DIMM1
  HSA  = PD_CHG_CPU1_DIMM1_SAA
  RFU2  = TP_CHG_CPU1_DIMM1_FRU_2
  RFU3  = TP_CHG_CPU1_DIMM1_FRU_3
  VSS64  = GND
  DQ2_A  = M_G_CPU1_SA_DQ<2>
  VSS65  = GND
  DQ3_A  = M_G_CPU1_SA_DQ<3>
  VSS66  = GND
  \dqs5_a_c||tdqs5_a_c||dqs5_a_t||tdqs5_a_t\  = M_G_CPU1_SA_DQS_DN<5>
  \dqs5_a_t||tdqs5_a_t\  = M_G_CPU1_SA_DQS_DP<5>
  VSS67  = GND
  DQ6_A  = M_G_CPU1_SA_DQ<6>
  VSS68  = GND
  DQ7_A  = M_G_CPU1_SA_DQ<7>
  VSS69  = GND
  DQ10_A  = M_G_CPU1_SA_DQ<10>
  VSS70  = GND
  DQ11_A  = M_G_CPU1_SA_DQ<11>
  VSS71  = GND
  \dqs6_a_c||tdqs6_a_c||dqs6_a_t||tdqs6_a_t\  = M_G_CPU1_SA_DQS_DN<6>
  \dqs6_a_t||tdqs6_a_t\  = M_G_CPU1_SA_DQS_DP<6>
  VSS72  = GND
  DQ14_A  = M_G_CPU1_SA_DQ<14>
  VSS73  = GND
  DQ15_A  = M_G_CPU1_SA_DQ<15>
  VSS74  = GND
  DQ18_A  = M_G_CPU1_SA_DQ<18>
  VSS75  = GND
  DQ19_A  = M_G_CPU1_SA_DQ<19>
  VSS76  = GND
  \dqs7_a_c||tdqs7_a_c\  = M_G_CPU1_SA_DQS_DN<7>
  \dqs7_a_t||tdqs7_a_t\  = M_G_CPU1_SA_DQS_DP<7>
  VSS77  = GND
  DQ22_A  = M_G_CPU1_SA_DQ<22>
  VSS78  = GND
  DQ23_A  = M_G_CPU1_SA_DQ<23>
  VSS79  = GND
  DQ26_A  = M_G_CPU1_SA_DQ<26>
  VSS80  = GND
  DQ27_A  = M_G_CPU1_SA_DQ<27>
  VSS81  = GND
  \dqs8_a_c||tdqs8_a_c\  = M_G_CPU1_SA_DQS_DN<8>
  \dqs8_a_t||tdqs8_a_t\  = M_G_CPU1_SA_DQS_DP<8>
  VSS82  = GND
  DQ30_A  = M_G_CPU1_SA_DQ<30>
  VSS83  = GND
  DQ31_A  = M_G_CPU1_SA_DQ<31>
  VSS84  = GND
  CB2_A  = M_G_CPU1_SA_CB<2>
  VSS85  = GND
  CB3_A  = M_G_CPU1_SA_CB<3>
  VSS86  = GND
  \dqs9_a_c||tdqs9_a_c\  = M_G_CPU1_SA_DQS_DN<9>
  \dqs9_a_t||tdqs9_a_t\  = M_G_CPU1_SA_DQS_DP<9>
  VSS87  = GND
  CB6_A  = M_G_CPU1_SA_CB<6>
  VSS88  = GND
  CB7_A  = M_G_CPU1_SA_CB<7>
  VSS89  = GND
  RESET_N  = RST_M_GH_CPU1_FPGA_N
  VSS90  = GND
  CS1_A_N  = M_G_CPU1_SA_CS_N<1>
  VSS91  = GND
  CA1_A  = M_G_CPU1_SA_CA<1>
  VSS92  = GND
  CA3_A  = M_G_CPU1_SA_CA<3>
  VSS93  = GND
  CA5_A  = M_G_CPU1_SA_CA<5>
  VSS94  = GND
  CK_T  = M_G_CPU1_CLK_DP<0>
  CK_C  = M_G_CPU1_CLK_DN<0>
  VSS95  = GND
  RFU4  = TP_CHG_CPU1_DIMM1_FRU_4
  CA1_B  = M_G_CPU1_SB_CA<1>
  VSS96  = GND
  CA3_B  = M_G_CPU1_SB_CA<3>
  VSS97  = GND
  CA5_B  = M_G_CPU1_SB_CA<5>
  VSS98  = GND
  PAR_B  = M_G_CPU1_SB_PAR
  VSS99  = GND
  CS1_B_N  = M_G_CPU1_SB_CS_N<1>
  VSS100  = GND
  RFU5  = TP_CHG_CPU1_DIMM1_FRU_5
  RFU6  = TP_CHG_CPU1_DIMM1_FRU_6
  VSS101  = GND
  CB6_B  = M_G_CPU1_SB_CB<6>
  VSS102  = GND
  CB7_B  = M_G_CPU1_SB_CB<7>
  VSS103  = GND
  DQS4_B_C  = M_G_CPU1_SB_DQS_DN<4>
  DQS4_B_T  = M_G_CPU1_SB_DQS_DP<4>
  VSS104  = GND
  CB2_B  = M_G_CPU1_SB_CB<2>
  VSS105  = GND
  CB3_B  = M_G_CPU1_SB_CB<3>
  VSS106  = GND
  DQ2_B  = M_G_CPU1_SB_DQ<2>
  VSS107  = GND
  DQ3_B  = M_G_CPU1_SB_DQ<3>
  VSS108  = GND
  \dqs5_b_c||tdqs5_b_c\  = M_G_CPU1_SB_DQS_DN<5>
  \dqs5_b_t||tdqs5_b_t\  = M_G_CPU1_SB_DQS_DP<5>
  VSS109  = GND
  DQ6_B  = M_G_CPU1_SB_DQ<6>
  VSS110  = GND
  DQ7_B  = M_G_CPU1_SB_DQ<7>
  VSS111  = GND
  DQ10_B  = M_G_CPU1_SB_DQ<10>
  VSS112  = GND
  DQ11_B  = M_G_CPU1_SB_DQ<11>
  VSS113  = GND
  \dqs6_b_c||tdqs6_b_c\  = M_G_CPU1_SB_DQS_DN<6>
  \dqs6_b_t||tdqs6_b_t\  = M_G_CPU1_SB_DQS_DP<6>
  VSS114  = GND
  DQ14_B  = M_G_CPU1_SB_DQ<14>
  VSS115  = GND
  DQ15_B  = M_G_CPU1_SB_DQ<15>
  VSS116  = GND
  DQ18_B  = M_G_CPU1_SB_DQ<18>
  VSS117  = GND
  DQ19_B  = M_G_CPU1_SB_DQ<19>
  VSS118  = GND
  \dqs7_b_c||tdqs7_b_c\  = M_G_CPU1_SB_DQS_DN<7>
  \dqs7_b_t||tdqs7_b_t\  = M_G_CPU1_SB_DQS_DP<7>
  VSS119  = GND
  DQ22_B  = M_G_CPU1_SB_DQ<22>
  VSS120  = GND
  DQ23_B  = M_G_CPU1_SB_DQ<23>
  VSS121  = GND
  DQ26_B  = M_G_CPU1_SB_DQ<26>
  VSS122  = GND
  DQ27_B  = M_G_CPU1_SB_DQ<27>
  VSS123  = GND
  \dqs8_b_c||tdqs8_b_c\  = M_G_CPU1_SB_DQS_DN<8>
  \dqs8_b_t||tdqs8_b_t\  = M_G_CPU1_SB_DQS_DP<8>
  VSS124  = GND
  DQ30_B  = M_G_CPU1_SB_DQ<30>
  VSS125  = GND
  DQ31_B  = M_G_CPU1_SB_DQ<31>
  VSS126  = GND
  G1  = GND
  G2  = GND
  G3  = GND

(kicad_pcb
	(version 20260206)
	(generator "pcbnew")
	(generator_version "10.0")
	(general
		(thickness 1.6)
		(legacy_teardrops no)
	)
	(paper "A4")
	(title_block
		(title "03242023_DA0F0TMBIJ0_F0T_Motherboard_J_brd_V01_OCP.brd")
		(comment 1 "Grand Teton / footprint 2874 of 6105 (J29), pads 1-45 of 291")
	)
	(layers
		(0 "F.Cu" signal "TOP")
		(4 "In1.Cu" signal "GND")
		(6 "In2.Cu" signal "IN1")
		(8 "In3.Cu" signal "GND1")
		(10 "In4.Cu" signal "IN2")
		(12 "In5.Cu" signal "GND2")
		(14 "In6.Cu" signal "IN3")
		(16 "In7.Cu" signal "GND3")
		(18 "In8.Cu" signal "VCC")
		(20 "In9.Cu" signal "VCC1")
		(22 "In10.Cu" signal "GND4")
		(24 "In11.Cu" signal "IN4")
		(26 "In12.Cu" signal "GND5")
		(28 "In13.Cu" signal "IN5")
		(30 "In14.Cu" signal "GND6")
		(32 "In15.Cu" signal "IN6")
		(34 "In16.Cu" signal "GND7")
		(2 "B.Cu" signal "BOTTOM")
		(9 "F.Adhes" user "F.Adhesive")
		(11 "B.Adhes" user "B.Adhesive")
		(13 "F.Paste" user "Package Geometry/Pastemask Top")
		(15 "B.Paste" user "Package Geometry/Pastemask Bottom")
		(5 "F.SilkS" user "Ref Des/Silkscreen Top")
		(7 "B.SilkS" user "Ref Des/Silkscreen Bottom")
		(1 "F.Mask" user "Board Geometry/Soldermask Top")
		(3 "B.Mask" user "Board Geometry/Soldermask Bottom")
		(17 "Dwgs.User" user "User.Drawings")
		(19 "Cmts.User" user "User.Comments")
		(21 "Eco1.User" user "User.Eco1")
		(23 "Eco2.User" user "User.Eco2")
		(25 "Edge.Cuts" user "Board Geometry/Outline")
		(27 "Margin" user)
		(31 "F.CrtYd" user "Package Geometry/Place Bound Top")
		(29 "B.CrtYd" user "Package Geometry/Place Bound Bottom")
		(35 "F.Fab" user "Ref Des/Assembly Top")
		(33 "B.Fab" user "Ref Des/Assembly Bottom")
	)
	(footprint ""
		(layer "F.Cu")
		(at 198.58228 -258.091686)
		(property "Reference" "J29"
			(at -3.683 -81.702148 0)
			(unlocked yes)
			(layer "F.SilkS")
			(effects
				(font
					(size 0.7874 0.5842)
					(thickness 0.1524)
				)
				(justify left)
			)
		)
		(property "Value" ""
			(at 0 0 0)
			(layer "F.Fab")
			(effects
				(font
					(size 1.27 1.27)
				)
			)
		)
		(duplicate_pad_numbers_are_jumpers no)
		(pad "1" smd rect
			(at -2.050034 -63.324994 270)
			(size 0.519938 1.4986)
			(layers "F.Cu" "F.Mask" "F.Paste")
			(net "P12V_S3_AUX_CPU1_NVDIMM")
		)
		(pad "2" smd rect
			(at -2.050034 -62.47511 270)
			(size 0.519938 1.4986)
			(layers "F.Cu" "F.Mask" "F.Paste")
			(net "TP_CHG_CPU1_DIMM1_FRU_0")
		)
		(pad "3" smd rect
			(at -2.050034 -61.624972 270)
			(size 0.519938 1.4986)
			(layers "F.Cu" "F.Mask" "F.Paste")
			(net "P3V3_AUX")
		)
		(pad "4" smd rect
			(at -2.050034 -60.775088 270)
			(size 0.519938 1.4986)
			(layers "F.Cu" "F.Mask" "F.Paste")
			(net "I3C_SPD_DDREFGH_CPU1_LVC1_SCL_4")
		)
		(pad "5" smd rect
			(at -2.050034 -59.92495 270)
			(size 0.519938 1.4986)
			(layers "F.Cu" "F.Mask" "F.Paste")
			(net "I3C_SPD_DDREFGH_CPU1_LVC1_SDA")
		)
		(pad "6" smd rect
			(at -2.050034 -59.075066 270)
			(size 0.519938 1.4986)
			(layers "F.Cu" "F.Mask" "F.Paste")
			(net "GND")
		)
		(pad "7" smd rect
			(at -2.050034 -58.224928 270)
			(size 0.519938 1.4986)
			(layers "F.Cu" "F.Mask" "F.Paste")
			(net "M_G_CPU1_SA_DQ<0>")
		)
		(pad "8" smd rect
			(at -2.050034 -57.375044 270)
			(size 0.519938 1.4986)
			(layers "F.Cu" "F.Mask" "F.Paste")
			(net "GND")
		)
		(pad "9" smd rect
			(at -2.050034 -56.524906 270)
			(size 0.519938 1.4986)
			(layers "F.Cu" "F.Mask" "F.Paste")
			(net "M_G_CPU1_SA_DQ<1>")
		)
		(pad "10" smd rect
			(at -2.050034 -55.675022 270)
			(size 0.519938 1.4986)
			(layers "F.Cu" "F.Mask" "F.Paste")
			(net "GND")
		)
		(pad "11" smd rect
			(at -2.050034 -54.824884 270)
			(size 0.519938 1.4986)
			(layers "F.Cu" "F.Mask" "F.Paste")
			(net "M_G_CPU1_SA_DQS_DP<0>")
		)
		(pad "12" smd rect
			(at -2.050034 -53.975 270)
			(size 0.519938 1.4986)
			(layers "F.Cu" "F.Mask" "F.Paste")
			(net "M_G_CPU1_SA_DQS_DN<0>")
		)
		(pad "13" smd rect
			(at -2.050034 -53.125116 270)
			(size 0.519938 1.4986)
			(layers "F.Cu" "F.Mask" "F.Paste")
			(net "GND")
		)
		(pad "14" smd rect
			(at -2.050034 -52.274978 270)
			(size 0.519938 1.4986)
			(layers "F.Cu" "F.Mask" "F.Paste")
			(net "M_G_CPU1_SA_DQ<4>")
		)
		(pad "15" smd rect
			(at -2.050034 -51.425094 270)
			(size 0.519938 1.4986)
			(layers "F.Cu" "F.Mask" "F.Paste")
			(net "GND")
		)
		(pad "16" smd rect
			(at -2.050034 -50.574956 270)
			(size 0.519938 1.4986)
			(layers "F.Cu" "F.Mask" "F.Paste")
			(net "M_G_CPU1_SA_DQ<5>")
		)
		(pad "17" smd rect
			(at -2.050034 -49.725072 270)
			(size 0.519938 1.4986)
			(layers "F.Cu" "F.Mask" "F.Paste")
			(net "GND")
		)
		(pad "18" smd rect
			(at -2.050034 -48.874934 270)
			(size 0.519938 1.4986)
			(layers "F.Cu" "F.Mask" "F.Paste")
			(net "M_G_CPU1_SA_DQ<8>")
		)
		(pad "19" smd rect
			(at -2.050034 -48.02505 270)
			(size 0.519938 1.4986)
			(layers "F.Cu" "F.Mask" "F.Paste")
			(net "GND")
		)
		(pad "20" smd rect
			(at -2.050034 -47.174912 270)
			(size 0.519938 1.4986)
			(layers "F.Cu" "F.Mask" "F.Paste")
			(net "M_G_CPU1_SA_DQ<9>")
		)
		(pad "21" smd rect
			(at -2.050034 -46.325028 270)
			(size 0.519938 1.4986)
			(layers "F.Cu" "F.Mask" "F.Paste")
			(net "GND")
		)
		(pad "22" smd rect
			(at -2.050034 -45.47489 270)
			(size 0.519938 1.4986)
			(layers "F.Cu" "F.Mask" "F.Paste")
			(net "M_G_CPU1_SA_DQS_DP<1>")
		)
		(pad "23" smd rect
			(at -2.050034 -44.625006 270)
			(size 0.519938 1.4986)
			(layers "F.Cu" "F.Mask" "F.Paste")
			(net "M_G_CPU1_SA_DQS_DN<1>")
		)
		(pad "24" smd rect
			(at -2.050034 -43.775122 270)
			(size 0.519938 1.4986)
			(layers "F.Cu" "F.Mask" "F.Paste")
			(net "GND")
		)
		(pad "25" smd rect
			(at -2.050034 -42.924984 270)
			(size 0.519938 1.4986)
			(layers "F.Cu" "F.Mask" "F.Paste")
			(net "M_G_CPU1_SA_DQ<12>")
		)
		(pad "26" smd rect
			(at -2.050034 -42.0751 270)
			(size 0.519938 1.4986)
			(layers "F.Cu" "F.Mask" "F.Paste")
			(net "GND")
		)
		(pad "27" smd rect
			(at -2.050034 -41.224962 270)
			(size 0.519938 1.4986)
			(layers "F.Cu" "F.Mask" "F.Paste")
			(net "M_G_CPU1_SA_DQ<13>")
		)
		(pad "28" smd rect
			(at -2.050034 -40.375078 270)
			(size 0.519938 1.4986)
			(layers "F.Cu" "F.Mask" "F.Paste")
			(net "GND")
		)
		(pad "29" smd rect
			(at -2.050034 -39.52494 270)
			(size 0.519938 1.4986)
			(layers "F.Cu" "F.Mask" "F.Paste")
			(net "M_G_CPU1_SA_DQ<16>")
		)
		(pad "30" smd rect
			(at -2.050034 -38.675056 270)
			(size 0.519938 1.4986)
			(layers "F.Cu" "F.Mask" "F.Paste")
			(net "GND")
		)
		(pad "31" smd rect
			(at -2.050034 -37.824918 270)
			(size 0.519938 1.4986)
			(layers "F.Cu" "F.Mask" "F.Paste")
			(net "M_G_CPU1_SA_DQ<17>")
		)
		(pad "32" smd rect
			(at -2.050034 -36.975034 270)
			(size 0.519938 1.4986)
			(layers "F.Cu" "F.Mask" "F.Paste")
			(net "GND")
		)
		(pad "33" smd rect
			(at -2.050034 -36.124896 270)
			(size 0.519938 1.4986)
			(layers "F.Cu" "F.Mask" "F.Paste")
			(net "M_G_CPU1_SA_DQS_DP<2>")
		)
		(pad "34" smd rect
			(at -2.050034 -35.275012 270)
			(size 0.519938 1.4986)
			(layers "F.Cu" "F.Mask" "F.Paste")
			(net "M_G_CPU1_SA_DQS_DN<2>")
		)
		(pad "35" smd rect
			(at -2.050034 -34.425128 270)
			(size 0.519938 1.4986)
			(layers "F.Cu" "F.Mask" "F.Paste")
			(net "GND")
		)
		(pad "36" smd rect
			(at -2.050034 -33.57499 270)
			(size 0.519938 1.4986)
			(layers "F.Cu" "F.Mask" "F.Paste")
			(net "M_G_CPU1_SA_DQ<20>")
		)
		(pad "37" smd rect
			(at -2.050034 -32.725106 270)
			(size 0.519938 1.4986)
			(layers "F.Cu" "F.Mask" "F.Paste")
			(net "GND")
		)
		(pad "38" smd rect
			(at -2.050034 -31.874968 270)
			(size 0.519938 1.4986)
			(layers "F.Cu" "F.Mask" "F.Paste")
			(net "M_G_CPU1_SA_DQ<21>")
		)
		(pad "39" smd rect
			(at -2.050034 -31.025084 270)
			(size 0.519938 1.4986)
			(layers "F.Cu" "F.Mask" "F.Paste")
			(net "GND")
		)
		(pad "40" smd rect
			(at -2.050034 -30.174946 270)
			(size 0.519938 1.4986)
			(layers "F.Cu" "F.Mask" "F.Paste")
			(net "M_G_CPU1_SA_DQ<24>")
		)
		(pad "41" smd rect
			(at -2.050034 -29.325062 270)
			(size 0.519938 1.4986)
			(layers "F.Cu" "F.Mask" "F.Paste")
			(net "GND")
		)
		(pad "42" smd rect
			(at -2.050034 -28.474924 270)
			(size 0.519938 1.4986)
			(layers "F.Cu" "F.Mask" "F.Paste")
			(net "M_G_CPU1_SA_DQ<25>")
		)
		(pad "43" smd rect
			(at -2.050034 -27.62504 270)
			(size 0.519938 1.4986)
			(layers "F.Cu" "F.Mask" "F.Paste")
			(net "GND")
		)
		(pad "44" smd rect
			(at -2.050034 -26.774902 270)
			(size 0.519938 1.4986)
			(layers "F.Cu" "F.Mask" "F.Paste")
			(net "M_G_CPU1_SA_DQS_DP<3>")
		)
		(pad "45" smd rect
			(at -2.050034 -25.925018 270)
			(size 0.519938 1.4986)
			(layers "F.Cu" "F.Mask" "F.Paste")
			(net "M_G_CPU1_SA_DQS_DN<3>")
		)
	)
)
